(kicad_pcb
	(version 20260206)
	(generator "pcbnew")
	(generator_version "10.0")
	(general
		(thickness 1.6)
		(legacy_teardrops no)
	)
	(paper "A4")
	(title_block
		(title "12092022_DA0F0TFB6D0_F0T_FAN_BOARD_MP5048_D_brd_v02_OCP.brd")
		(comment 1 "Grand Teton / footprints 340-345 of 924")
	)
	(layers
		(0 "F.Cu" signal "TOP")
		(4 "In1.Cu" signal "GND")
		(6 "In2.Cu" signal "IN1")
		(8 "In3.Cu" signal "IN2")
		(10 "In4.Cu" signal "GND1")
		(2 "B.Cu" signal "BOTTOM")
		(9 "F.Adhes" user "F.Adhesive")
		(11 "B.Adhes" user "B.Adhesive")
		(13 "F.Paste" user "Package Geometry/Pastemask Top")
		(15 "B.Paste" user "Package Geometry/Pastemask Bottom")
		(5 "F.SilkS" user "Ref Des/Silkscreen Top")
		(7 "B.SilkS" user "Ref Des/Silkscreen Bottom")
		(1 "F.Mask" user "Board Geometry/Soldermask Top")
		(3 "B.Mask" user "Board Geometry/Soldermask Bottom")
		(17 "Dwgs.User" user "User.Drawings")
		(19 "Cmts.User" user "User.Comments")
		(21 "Eco1.User" user "User.Eco1")
		(23 "Eco2.User" user "User.Eco2")
		(25 "Edge.Cuts" user "Board Geometry/Outline")
		(27 "Margin" user)
		(31 "F.CrtYd" user "Package Geometry/Place Bound Top")
		(29 "B.CrtYd" user "Package Geometry/Place Bound Bottom")
		(35 "F.Fab" user "Ref Des/Assembly Top")
		(33 "B.Fab" user "Ref Des/Assembly Bottom")
	)
	(footprint ""
		(layer "F.Cu")
		(at 18.679922 -286.6771 180)
		(property "Reference" "D261"
			(at 1.407922 -1.58877 0)
			(unlocked yes)
			(layer "F.SilkS")
			(effects
				(font
					(size 0.7874 0.5842)
					(thickness 0.1524)
				)
				(justify left)
			)
		)
		(property "Value" ""
			(at 0 0 180)
			(layer "F.Fab")
			(effects
				(font
					(size 1.27 1.27)
				)
			)
		)
		(duplicate_pad_numbers_are_jumpers no)
		(fp_line
			(start 0.94488 0.450088)
			(end 0.94488 -0.450088)
			(stroke
				(width 0.1524)
				(type default)
			)
			(layer "F.SilkS")
		)
		(fp_line
			(start 0.94488 -0.450088)
			(end -0.854964 -0.450088)
			(stroke
				(width 0.1524)
				(type default)
			)
			(layer "F.SilkS")
		)
		(fp_line
			(start 0.870458 -0.2794)
			(end 0.845058 0.4064)
			(stroke
				(width 0.1524)
				(type default)
			)
			(layer "F.SilkS")
		)
		(fp_line
			(start 0.845058 0.4064)
			(end 0.845058 -0.381)
			(stroke
				(width 0.1524)
				(type default)
			)
			(layer "F.SilkS")
		)
		(fp_line
			(start -0.854964 0.450088)
			(end 0.925068 0.450088)
			(stroke
				(width 0.1524)
				(type default)
			)
			(layer "F.SilkS")
		)
		(fp_line
			(start -0.854964 -0.450088)
			(end -0.854964 0.450088)
			(stroke
				(width 0.1524)
				(type default)
			)
			(layer "F.SilkS")
		)
		(fp_line
			(start 0.54991 0.350012)
			(end 0.54991 -0.350012)
			(stroke
				(width 0.1)
				(type default)
			)
			(layer "F.Fab")
		)
		(fp_line
			(start 0.54991 -0.350012)
			(end -0.54991 -0.350012)
			(stroke
				(width 0.1)
				(type default)
			)
			(layer "F.Fab")
		)
		(fp_line
			(start -0.54991 0.350012)
			(end 0.54991 0.350012)
			(stroke
				(width 0.1)
				(type default)
			)
			(layer "F.Fab")
		)
		(fp_line
			(start -0.54991 -0.350012)
			(end -0.54991 0.350012)
			(stroke
				(width 0.1)
				(type default)
			)
			(layer "F.Fab")
		)
		(fp_text user "-"
			(at 1.915922 -0.57785 0)
			(unlocked yes)
			(layer "F.SilkS")
			(effects
				(font
					(size 1.905 1.4224)
					(thickness 0.1524)
				)
				(justify left)
			)
		)
		(fp_text user "+"
			(at -1.132078 0.18415 0)
			(unlocked yes)
			(layer "F.SilkS")
			(effects
				(font
					(size 1.905 1.4224)
					(thickness 0.1524)
				)
				(justify left)
			)
		)
		(fp_text user "-"
			(at 2.48539 0.239014 0)
			(unlocked yes)
			(layer "F.Fab")
			(effects
				(font
					(size 1.905 1.4224)
					(thickness 0.1524)
				)
				(justify left)
			)
		)
		(fp_text user "+"
			(at -0.808228 0.239014 0)
			(unlocked yes)
			(layer "F.Fab")
			(effects
				(font
					(size 1.905 1.4224)
					(thickness 0.1524)
				)
				(justify left)
			)
		)
		(pad "A" smd rect
			(at -0.424942 0 180)
			(size 0.5588 0.6096)
			(layers "F.Cu" "F.Mask" "F.Paste")
			(net "GND")
		)
		(pad "C" smd rect
			(at 0.424942 0)
			(size 0.5588 0.6096)
			(layers "F.Cu" "F.Mask" "F.Paste")
			(net "FAN_7_PWM_OL_R")
		)
	)
	(footprint ""
		(layer "F.Cu")
		(at 31.623 -121.92 90)
		(property "Reference" "R4782"
			(at 0 0 90)
			(layer "F.SilkS")
			(hide yes)
			(effects
				(font
					(size 1.27 1.27)
				)
			)
		)
		(property "Value" ""
			(at 0 0 90)
			(layer "F.Fab")
			(effects
				(font
					(size 1.27 1.27)
				)
			)
		)
		(duplicate_pad_numbers_are_jumpers no)
		(fp_line
			(start 0.7874 -0.4064)
			(end 0.7874 0.4064)
			(stroke
				(width 0.1524)
				(type default)
			)
			(layer "F.SilkS")
		)
		(fp_line
			(start -0.7874 -0.4064)
			(end 0.7874 -0.4064)
			(stroke
				(width 0.1524)
				(type default)
			)
			(layer "F.SilkS")
		)
		(fp_line
			(start 0.7874 0.4064)
			(end -0.7874 0.4064)
			(stroke
				(width 0.1524)
				(type default)
			)
			(layer "F.SilkS")
		)
		(fp_line
			(start -0.7874 0.4064)
			(end -0.7874 -0.4064)
			(stroke
				(width 0.1524)
				(type default)
			)
			(layer "F.SilkS")
		)
		(fp_line
			(start -0.12065 -0.305054)
			(end -0.12065 -0.2794)
			(stroke
				(width 0.1)
				(type default)
			)
			(layer "F.Fab")
		)
		(fp_line
			(start -0.67945 -0.305054)
			(end -0.12065 -0.305054)
			(stroke
				(width 0.1)
				(type default)
			)
			(layer "F.Fab")
		)
		(fp_line
			(start 0.67945 -0.3048)
			(end 0.67945 0.3048)
			(stroke
				(width 0.1)
				(type default)
			)
			(layer "F.Fab")
		)
		(fp_line
			(start 0.12065 -0.3048)
			(end 0.67945 -0.3048)
			(stroke
				(width 0.1)
				(type default)
			)
			(layer "F.Fab")
		)
		(fp_line
			(start 0.12065 -0.2794)
			(end 0.12065 -0.3048)
			(stroke
				(width 0.1)
				(type default)
			)
			(layer "F.Fab")
		)
		(fp_line
			(start -0.12065 -0.2794)
			(end 0.12065 -0.2794)
			(stroke
				(width 0.1)
				(type default)
			)
			(layer "F.Fab")
		)
		(fp_line
			(start 0.120396 0.2794)
			(end -0.12065 0.2794)
			(stroke
				(width 0.1)
				(type default)
			)
			(layer "F.Fab")
		)
		(fp_line
			(start -0.12065 0.2794)
			(end -0.12065 0.3048)
			(stroke
				(width 0.1)
				(type default)
			)
			(layer "F.Fab")
		)
		(fp_line
			(start 0.67945 0.3048)
			(end 0.120396 0.3048)
			(stroke
				(width 0.1)
				(type default)
			)
			(layer "F.Fab")
		)
		(fp_line
			(start 0.120396 0.3048)
			(end 0.120396 0.2794)
			(stroke
				(width 0.1)
				(type default)
			)
			(layer "F.Fab")
		)
		(fp_line
			(start -0.12065 0.3048)
			(end -0.67945 0.3048)
			(stroke
				(width 0.1)
				(type default)
			)
			(layer "F.Fab")
		)
		(fp_line
			(start -0.67945 0.3048)
			(end -0.67945 -0.305054)
			(stroke
				(width 0.1)
				(type default)
			)
			(layer "F.Fab")
		)
		(pad "1" smd circle
			(at -0.40005 0 90)
			(size 0 0)
			(layers "F.Cu" "F.Mask" "F.Paste")
			(net "GND")
		)
		(pad "2" smd circle
			(at 0.40005 0 90)
			(size 0 0)
			(layers "F.Cu" "F.Mask" "F.Paste")
			(net "MAX31790_U317_ADD1")
		)
	)
	(footprint ""
		(layer "F.Cu")
		(at 36.322 -208.308956)
		(property "Reference" "D272"
			(at 2.794 -0.706374 0)
			(unlocked yes)
			(layer "F.SilkS")
			(effects
				(font
					(size 0.7874 0.5842)
					(thickness 0.1524)
				)
				(justify left)
			)
		)
		(property "Value" ""
			(at 0 0 0)
			(layer "F.Fab")
			(effects
				(font
					(size 1.27 1.27)
				)
			)
		)
		(duplicate_pad_numbers_are_jumpers no)
		(fp_line
			(start -0.854964 -0.450088)
			(end -0.854964 0.450088)
			(stroke
				(width 0.1524)
				(type default)
			)
			(layer "F.SilkS")
		)
		(fp_line
			(start -0.854964 0.450088)
			(end 0.925068 0.450088)
			(stroke
				(width 0.1524)
				(type default)
			)
			(layer "F.SilkS")
		)
		(fp_line
			(start 0.845058 0.4064)
			(end 0.845058 -0.381)
			(stroke
				(width 0.1524)
				(type default)
			)
			(layer "F.SilkS")
		)
		(fp_line
			(start 0.870458 -0.2794)
			(end 0.845058 0.4064)
			(stroke
				(width 0.1524)
				(type default)
			)
			(layer "F.SilkS")
		)
		(fp_line
			(start 0.94488 -0.450088)
			(end -0.854964 -0.450088)
			(stroke
				(width 0.1524)
				(type default)
			)
			(layer "F.SilkS")
		)
		(fp_line
			(start 0.94488 0.450088)
			(end 0.94488 -0.450088)
			(stroke
				(width 0.1524)
				(type default)
			)
			(layer "F.SilkS")
		)
		(fp_line
			(start -0.54991 -0.350012)
			(end -0.54991 0.350012)
			(stroke
				(width 0.1)
				(type default)
			)
			(layer "F.Fab")
		)
		(fp_line
			(start -0.54991 0.350012)
			(end 0.54991 0.350012)
			(stroke
				(width 0.1)
				(type default)
			)
			(layer "F.Fab")
		)
		(fp_line
			(start 0.54991 -0.350012)
			(end -0.54991 -0.350012)
			(stroke
				(width 0.1)
				(type default)
			)
			(layer "F.Fab")
		)
		(fp_line
			(start 0.54991 0.350012)
			(end 0.54991 -0.350012)
			(stroke
				(width 0.1)
				(type default)
			)
			(layer "F.Fab")
		)
		(fp_text user "+"
			(at -0.681228 0.239014 180)
			(unlocked yes)
			(layer "F.SilkS")
			(effects
				(font
					(size 1.905 1.4224)
					(thickness 0.1524)
				)
				(justify left)
			)
		)
		(fp_text user "-"
			(at 2.159 0.251206 180)
			(unlocked yes)
			(layer "F.SilkS")
			(effects
				(font
					(size 1.905 1.4224)
					(thickness 0.1524)
				)
				(justify left)
			)
		)
		(fp_text user "+"
			(at -0.808228 0.239014 180)
			(unlocked yes)
			(layer "F.Fab")
			(effects
				(font
					(size 1.905 1.4224)
					(thickness 0.1524)
				)
				(justify left)
			)
		)
		(fp_text user "-"
			(at 2.48539 0.239014 180)
			(unlocked yes)
			(layer "F.Fab")
			(effects
				(font
					(size 1.905 1.4224)
					(thickness 0.1524)
				)
				(justify left)
			)
		)
		(pad "A" smd rect
			(at -0.424942 0)
			(size 0.5588 0.6096)
			(layers "F.Cu" "F.Mask" "F.Paste")
			(net "GND")
		)
		(pad "C" smd rect
			(at 0.424942 0 180)
			(size 0.5588 0.6096)
			(layers "F.Cu" "F.Mask" "F.Paste")
			(net "FAN_1_TACH_IL_D")
		)
	)
	(footprint ""
		(layer "F.Cu")
		(at 30.734 -162.941 90)
		(property "Reference" "R5271"
			(at 0 0 90)
			(layer "F.SilkS")
			(hide yes)
			(effects
				(font
					(size 1.27 1.27)
				)
			)
		)
		(property "Value" ""
			(at 0 0 90)
			(layer "F.Fab")
			(effects
				(font
					(size 1.27 1.27)
				)
			)
		)
		(duplicate_pad_numbers_are_jumpers no)
		(fp_line
			(start 0.7874 -0.4064)
			(end 0.7874 0.4064)
			(stroke
				(width 0.1524)
				(type default)
			)
			(layer "F.SilkS")
		)
		(fp_line
			(start -0.7874 -0.4064)
			(end 0.7874 -0.4064)
			(stroke
				(width 0.1524)
				(type default)
			)
			(layer "F.SilkS")
		)
		(fp_line
			(start 0.7874 0.4064)
			(end -0.7874 0.4064)
			(stroke
				(width 0.1524)
				(type default)
			)
			(layer "F.SilkS")
		)
		(fp_line
			(start -0.7874 0.4064)
			(end -0.7874 -0.4064)
			(stroke
				(width 0.1524)
				(type default)
			)
			(layer "F.SilkS")
		)
		(fp_line
			(start -0.12065 -0.305054)
			(end -0.12065 -0.2794)
			(stroke
				(width 0.1)
				(type default)
			)
			(layer "F.Fab")
		)
		(fp_line
			(start -0.67945 -0.305054)
			(end -0.12065 -0.305054)
			(stroke
				(width 0.1)
				(type default)
			)
			(layer "F.Fab")
		)
		(fp_line
			(start 0.67945 -0.3048)
			(end 0.67945 0.3048)
			(stroke
				(width 0.1)
				(type default)
			)
			(layer "F.Fab")
		)
		(fp_line
			(start 0.12065 -0.3048)
			(end 0.67945 -0.3048)
			(stroke
				(width 0.1)
				(type default)
			)
			(layer "F.Fab")
		)
		(fp_line
			(start 0.12065 -0.2794)
			(end 0.12065 -0.3048)
			(stroke
				(width 0.1)
				(type default)
			)
			(layer "F.Fab")
		)
		(fp_line
			(start -0.12065 -0.2794)
			(end 0.12065 -0.2794)
			(stroke
				(width 0.1)
				(type default)
			)
			(layer "F.Fab")
		)
		(fp_line
			(start 0.120396 0.2794)
			(end -0.12065 0.2794)
			(stroke
				(width 0.1)
				(type default)
			)
			(layer "F.Fab")
		)
		(fp_line
			(start -0.12065 0.2794)
			(end -0.12065 0.3048)
			(stroke
				(width 0.1)
				(type default)
			)
			(layer "F.Fab")
		)
		(fp_line
			(start 0.67945 0.3048)
			(end 0.120396 0.3048)
			(stroke
				(width 0.1)
				(type default)
			)
			(layer "F.Fab")
		)
		(fp_line
			(start 0.120396 0.3048)
			(end 0.120396 0.2794)
			(stroke
				(width 0.1)
				(type default)
			)
			(layer "F.Fab")
		)
		(fp_line
			(start -0.12065 0.3048)
			(end -0.67945 0.3048)
			(stroke
				(width 0.1)
				(type default)
			)
			(layer "F.Fab")
		)
		(fp_line
			(start -0.67945 0.3048)
			(end -0.67945 -0.305054)
			(stroke
				(width 0.1)
				(type default)
			)
			(layer "F.Fab")
		)
		(pad "1" smd circle
			(at -0.40005 0 90)
			(size 0 0)
			(layers "F.Cu" "F.Mask" "F.Paste")
			(net "SMB_FAN5_R_SDA")
		)
		(pad "2" smd circle
			(at 0.40005 0 90)
			(size 0 0)
			(layers "F.Cu" "F.Mask" "F.Paste")
			(net "P3V3_AUX")
		)
	)
	(footprint ""
		(layer "F.Cu")
		(at 37.338 -105.086912)
		(property "Reference" "D276"
			(at 1.32334 -0.098298 0)
			(unlocked yes)
			(layer "F.SilkS")
			(effects
				(font
					(size 0.7874 0.5842)
					(thickness 0.1524)
				)
				(justify left)
			)
		)
		(property "Value" ""
			(at 0 0 0)
			(layer "F.Fab")
			(effects
				(font
					(size 1.27 1.27)
				)
			)
		)
		(duplicate_pad_numbers_are_jumpers no)
		(fp_line
			(start -0.854964 -0.450088)
			(end -0.854964 0.450088)
			(stroke
				(width 0.1524)
				(type default)
			)
			(layer "F.SilkS")
		)
		(fp_line
			(start -0.854964 0.450088)
			(end 0.925068 0.450088)
			(stroke
				(width 0.1524)
				(type default)
			)
			(layer "F.SilkS")
		)
		(fp_line
			(start 0.845058 0.4064)
			(end 0.845058 -0.381)
			(stroke
				(width 0.1524)
				(type default)
			)
			(layer "F.SilkS")
		)
		(fp_line
			(start 0.870458 -0.2794)
			(end 0.845058 0.4064)
			(stroke
				(width 0.1524)
				(type default)
			)
			(layer "F.SilkS")
		)
		(fp_line
			(start 0.94488 -0.450088)
			(end -0.854964 -0.450088)
			(stroke
				(width 0.1524)
				(type default)
			)
			(layer "F.SilkS")
		)
		(fp_line
			(start 0.94488 0.450088)
			(end 0.94488 -0.450088)
			(stroke
				(width 0.1524)
				(type default)
			)
			(layer "F.SilkS")
		)
		(fp_line
			(start -0.54991 -0.350012)
			(end -0.54991 0.350012)
			(stroke
				(width 0.1)
				(type default)
			)
			(layer "F.Fab")
		)
		(fp_line
			(start -0.54991 0.350012)
			(end 0.54991 0.350012)
			(stroke
				(width 0.1)
				(type default)
			)
			(layer "F.Fab")
		)
		(fp_line
			(start 0.54991 -0.350012)
			(end -0.54991 -0.350012)
			(stroke
				(width 0.1)
				(type default)
			)
			(layer "F.Fab")
		)
		(fp_line
			(start 0.54991 0.350012)
			(end 0.54991 -0.350012)
			(stroke
				(width 0.1)
				(type default)
			)
			(layer "F.Fab")
		)
		(fp_text user "+"
			(at -0.381 -0.408178 180)
			(unlocked yes)
			(layer "F.SilkS")
			(effects
				(font
					(size 1.905 1.4224)
					(thickness 0.1524)
				)
				(justify left)
			)
		)
		(fp_text user "-"
			(at 1.27 -0.608838 180)
			(unlocked yes)
			(layer "F.SilkS")
			(effects
				(font
					(size 1.905 1.4224)
					(thickness 0.1524)
				)
				(justify left)
			)
		)
		(fp_text user "+"
			(at -0.808228 0.239014 180)
			(unlocked yes)
			(layer "F.Fab")
			(effects
				(font
					(size 1.905 1.4224)
					(thickness 0.1524)
				)
				(justify left)
			)
		)
		(fp_text user "-"
			(at 2.48539 0.239014 180)
			(unlocked yes)
			(layer "F.Fab")
			(effects
				(font
					(size 1.905 1.4224)
					(thickness 0.1524)
				)
				(justify left)
			)
		)
		(pad "A" smd rect
			(at -0.424942 0)
			(size 0.5588 0.6096)
			(layers "F.Cu" "F.Mask" "F.Paste")
			(net "GND")
		)
		(pad "C" smd rect
			(at 0.424942 0 180)
			(size 0.5588 0.6096)
			(layers "F.Cu" "F.Mask" "F.Paste")
			(net "FAN_2_OK_R_LED_N")
		)
	)
	(footprint ""
		(layer "F.Cu")
		(at 11.557 -73.914 90)
		(property "Reference" "PR57"
			(at 0 0 90)
			(layer "F.SilkS")
			(hide yes)
			(effects
				(font
					(size 1.27 1.27)
				)
			)
		)
		(property "Value" ""
			(at 0 0 90)
			(layer "F.Fab")
			(effects
				(font
					(size 1.27 1.27)
				)
			)
		)
		(duplicate_pad_numbers_are_jumpers no)
		(fp_line
			(start 0.7874 -0.4064)
			(end 0.7874 0.4064)
			(stroke
				(width 0.1524)
				(type default)
			)
			(layer "F.SilkS")
		)
		(fp_line
			(start -0.7874 -0.4064)
			(end 0.7874 -0.4064)
			(stroke
				(width 0.1524)
				(type default)
			)
			(layer "F.SilkS")
		)
		(fp_line
			(start 0.7874 0.4064)
			(end -0.7874 0.4064)
			(stroke
				(width 0.1524)
				(type default)
			)
			(layer "F.SilkS")
		)
		(fp_line
			(start -0.7874 0.4064)
			(end -0.7874 -0.4064)
			(stroke
				(width 0.1524)
				(type default)
			)
			(layer "F.SilkS")
		)
		(fp_line
			(start -0.12065 -0.305054)
			(end -0.12065 -0.2794)
			(stroke
				(width 0.1)
				(type default)
			)
			(layer "F.Fab")
		)
		(fp_line
			(start -0.67945 -0.305054)
			(end -0.12065 -0.305054)
			(stroke
				(width 0.1)
				(type default)
			)
			(layer "F.Fab")
		)
		(fp_line
			(start 0.67945 -0.3048)
			(end 0.67945 0.3048)
			(stroke
				(width 0.1)
				(type default)
			)
			(layer "F.Fab")
		)
		(fp_line
			(start 0.12065 -0.3048)
			(end 0.67945 -0.3048)
			(stroke
				(width 0.1)
				(type default)
			)
			(layer "F.Fab")
		)
		(fp_line
			(start 0.12065 -0.2794)
			(end 0.12065 -0.3048)
			(stroke
				(width 0.1)
				(type default)
			)
			(layer "F.Fab")
		)
		(fp_line
			(start -0.12065 -0.2794)
			(end 0.12065 -0.2794)
			(stroke
				(width 0.1)
				(type default)
			)
			(layer "F.Fab")
		)
		(fp_line
			(start 0.120396 0.2794)
			(end -0.12065 0.2794)
			(stroke
				(width 0.1)
				(type default)
			)
			(layer "F.Fab")
		)
		(fp_line
			(start -0.12065 0.2794)
			(end -0.12065 0.3048)
			(stroke
				(width 0.1)
				(type default)
			)
			(layer "F.Fab")
		)
		(fp_line
			(start 0.67945 0.3048)
			(end 0.120396 0.3048)
			(stroke
				(width 0.1)
				(type default)
			)
			(layer "F.Fab")
		)
		(fp_line
			(start 0.120396 0.3048)
			(end 0.120396 0.2794)
			(stroke
				(width 0.1)
				(type default)
			)
			(layer "F.Fab")
		)
		(fp_line
			(start -0.12065 0.3048)
			(end -0.67945 0.3048)
			(stroke
				(width 0.1)
				(type default)
			)
			(layer "F.Fab")
		)
		(fp_line
			(start -0.67945 0.3048)
			(end -0.67945 -0.305054)
			(stroke
				(width 0.1)
				(type default)
			)
			(layer "F.Fab")
		)
		(pad "1" smd circle
			(at -0.40005 0 90)
			(size 0 0)
			(layers "F.Cu" "F.Mask" "F.Paste")
			(net "FAN_5_P3V_R")
		)
		(pad "2" smd circle
			(at 0.40005 0 90)
			(size 0 0)
			(layers "F.Cu" "F.Mask" "F.Paste")
			(net "FAN_5_MODE")
		)
	)
)
